(kicad_pcb
	(version 20260206)
	(generator "pcbnew")
	(generator_version "10.0")
	(general
		(thickness 1.6)
		(legacy_teardrops no)
	)
	(paper "A4")
	(title_block
		(title "v1-chassis-manager — T6M_CM_d_v01_1031_1645.brd")
		(comment 1 "Open CloudServer (Microsoft) / footprints 913-918 of 2512")
	)
	(layers
		(0 "F.Cu" signal "TOP")
		(4 "In1.Cu" signal "GND1")
		(6 "In2.Cu" signal "IN1")
		(8 "In3.Cu" signal "VCC1")
		(10 "In4.Cu" signal "VCC2")
		(12 "In5.Cu" signal "GND2")
		(14 "In6.Cu" signal "IN2")
		(16 "In7.Cu" signal "IN3")
		(18 "In8.Cu" signal "GND3")
		(2 "B.Cu" signal "BOTTOM")
		(9 "F.Adhes" user "F.Adhesive")
		(11 "B.Adhes" user "B.Adhesive")
		(13 "F.Paste" user "Package Geometry/Pastemask Top")
		(15 "B.Paste" user "Package Geometry/Pastemask Bottom")
		(5 "F.SilkS" user "Ref Des/Silkscreen Top")
		(7 "B.SilkS" user "Ref Des/Silkscreen Bottom")
		(1 "F.Mask" user "Board Geometry/Soldermask Top")
		(3 "B.Mask" user "Board Geometry/Soldermask Bottom")
		(17 "Dwgs.User" user "User.Drawings")
		(19 "Cmts.User" user "User.Comments")
		(21 "Eco1.User" user "User.Eco1")
		(23 "Eco2.User" user "User.Eco2")
		(25 "Edge.Cuts" user "Board Geometry/Outline")
		(27 "Margin" user)
		(31 "F.CrtYd" user "Package Geometry/Place Bound Top")
		(29 "B.CrtYd" user "Package Geometry/Place Bound Bottom")
		(35 "F.Fab" user "Ref Des/Assembly Top")
		(33 "B.Fab" user "Ref Des/Assembly Bottom")
	)
	(footprint ""
		(layer "F.Cu")
		(at 11.71956 -138.620246 -90)
		(property "Reference" "C562"
			(at 4.252468 5.096002 90)
			(unlocked yes)
			(layer "F.SilkS")
			(effects
				(font
					(size 0.7874 0.5842)
					(thickness 0.1524)
				)
				(justify left)
			)
		)
		(property "Value" ""
			(at 0 0 270)
			(layer "F.Fab")
			(effects
				(font
					(size 1.27 1.27)
				)
			)
		)
		(duplicate_pad_numbers_are_jumpers no)
		(fp_line
			(start -0.7874 0.4064)
			(end -0.7874 -0.4064)
			(stroke
				(width 0.1524)
				(type default)
			)
			(layer "F.SilkS")
		)
		(fp_line
			(start 0.7874 0.4064)
			(end -0.7874 0.4064)
			(stroke
				(width 0.1524)
				(type default)
			)
			(layer "F.SilkS")
		)
		(fp_line
			(start 0 0.381)
			(end 0 -0.381)
			(stroke
				(width 0.1524)
				(type default)
			)
			(layer "F.SilkS")
		)
		(fp_line
			(start -0.7874 -0.4064)
			(end 0.7874 -0.4064)
			(stroke
				(width 0.1524)
				(type default)
			)
			(layer "F.SilkS")
		)
		(fp_line
			(start 0.7874 -0.4064)
			(end 0.7874 0.4064)
			(stroke
				(width 0.1524)
				(type default)
			)
			(layer "F.SilkS")
		)
		(fp_poly
			(pts
				(xy -0.5334 0.254) (xy -0.635 0.254) (xy -0.635 0.2286) (xy -0.635 -0.254) (xy -0.5334 -0.254) (xy -0.5334 -0.2794)
				(xy 0.5334 -0.2794) (xy 0.5334 -0.254) (xy 0.635 -0.254) (xy 0.635 0.254) (xy 0.5334 0.254) (xy 0.5334 0.2794)
				(xy -0.508 0.2794) (xy -0.5334 0.2794)
			)
			(stroke
				(width 0)
				(type default)
			)
			(fill no)
			(layer "F.CrtYd")
		)
		(pad "1" smd rect
			(at 0.40005 0 270)
			(size 0.4572 0.508)
			(layers "F.Cu" "F.Mask" "F.Paste")
			(net "GND")
		)
		(pad "2" smd rect
			(at -0.40005 0 270)
			(size 0.4572 0.508)
			(layers "F.Cu" "F.Mask" "F.Paste")
			(net "N54310604")
		)
	)
	(footprint ""
		(layer "F.Cu")
		(at 75.18527 -119.870728)
		(property "Reference" "C202"
			(at -4.55422 0.23114 0)
			(unlocked yes)
			(layer "F.SilkS")
			(effects
				(font
					(size 0.7874 0.5842)
					(thickness 0.1524)
				)
				(justify left)
			)
		)
		(property "Value" ""
			(at 0 0 0)
			(layer "F.Fab")
			(effects
				(font
					(size 1.27 1.27)
				)
			)
		)
		(duplicate_pad_numbers_are_jumpers no)
		(fp_line
			(start -0.7874 -0.4064)
			(end 0.7874 -0.4064)
			(stroke
				(width 0.1524)
				(type default)
			)
			(layer "F.SilkS")
		)
		(fp_line
			(start -0.7874 0.4064)
			(end -0.7874 -0.4064)
			(stroke
				(width 0.1524)
				(type default)
			)
			(layer "F.SilkS")
		)
		(fp_line
			(start 0 0.381)
			(end 0 -0.381)
			(stroke
				(width 0.1524)
				(type default)
			)
			(layer "F.SilkS")
		)
		(fp_line
			(start 0.7874 -0.4064)
			(end 0.7874 0.4064)
			(stroke
				(width 0.1524)
				(type default)
			)
			(layer "F.SilkS")
		)
		(fp_line
			(start 0.7874 0.4064)
			(end -0.7874 0.4064)
			(stroke
				(width 0.1524)
				(type default)
			)
			(layer "F.SilkS")
		)
		(fp_poly
			(pts
				(xy -0.5334 0.254) (xy -0.635 0.254) (xy -0.635 0.2286) (xy -0.635 -0.254) (xy -0.5334 -0.254) (xy -0.5334 -0.2794)
				(xy 0.5334 -0.2794) (xy 0.5334 -0.254) (xy 0.635 -0.254) (xy 0.635 0.254) (xy 0.5334 0.254) (xy 0.5334 0.2794)
				(xy -0.508 0.2794) (xy -0.5334 0.2794)
			)
			(stroke
				(width 0)
				(type default)
			)
			(fill no)
			(layer "F.CrtYd")
		)
		(pad "1" smd rect
			(at 0.40005 0)
			(size 0.4572 0.508)
			(layers "F.Cu" "F.Mask" "F.Paste")
			(net "P2E_CPU_BMC_NODE1_RX_DP")
		)
		(pad "2" smd rect
			(at -0.40005 0)
			(size 0.4572 0.508)
			(layers "F.Cu" "F.Mask" "F.Paste")
			(net "P2E_CPU_BMC_NODE1_RX_C_DP")
		)
	)
	(footprint ""
		(layer "F.Cu")
		(at 42.332402 -145.804382 -90)
		(property "Reference" "R548"
			(at 0.86106 6.618732 90)
			(unlocked yes)
			(layer "F.SilkS")
			(effects
				(font
					(size 0.7874 0.5842)
					(thickness 0.1524)
				)
				(justify left)
			)
		)
		(property "Value" ""
			(at 0 0 270)
			(layer "F.Fab")
			(effects
				(font
					(size 1.27 1.27)
				)
			)
		)
		(duplicate_pad_numbers_are_jumpers no)
		(fp_line
			(start -0.7874 0.4064)
			(end -0.7874 -0.4064)
			(stroke
				(width 0.1524)
				(type default)
			)
			(layer "F.SilkS")
		)
		(fp_line
			(start 0.7874 0.4064)
			(end -0.7874 0.4064)
			(stroke
				(width 0.1524)
				(type default)
			)
			(layer "F.SilkS")
		)
		(fp_line
			(start -0.7874 -0.4064)
			(end 0.7874 -0.4064)
			(stroke
				(width 0.1524)
				(type default)
			)
			(layer "F.SilkS")
		)
		(fp_line
			(start 0.7874 -0.4064)
			(end 0.7874 0.4064)
			(stroke
				(width 0.1524)
				(type default)
			)
			(layer "F.SilkS")
		)
		(fp_poly
			(pts
				(xy -0.508 0.2794) (xy -0.508 0.2286) (xy -0.635 0.2286) (xy -0.635 -0.254) (xy -0.5334 -0.254)
				(xy -0.5334 -0.2794) (xy 0.5334 -0.2794) (xy 0.5334 -0.254) (xy 0.635 -0.254) (xy 0.635 0.254) (xy 0.5334 0.254)
				(xy 0.5334 0.2794)
			)
			(stroke
				(width 0)
				(type default)
			)
			(fill no)
			(layer "F.CrtYd")
		)
		(pad "1" smd rect
			(at 0.40005 0 270)
			(size 0.4572 0.508)
			(layers "F.Cu" "F.Mask" "F.Paste")
			(net "P3V3_NODE1")
		)
		(pad "2" smd rect
			(at -0.40005 0 270)
			(size 0.4572 0.508)
			(layers "F.Cu" "F.Mask" "F.Paste")
			(net "LAN1_NC_SI_RXD0")
		)
	)
	(footprint ""
		(layer "F.Cu")
		(at 149.213824 -20.568412 90)
		(property "Reference" "J6"
			(at -2.457196 3.232658 90)
			(unlocked yes)
			(layer "F.SilkS")
			(effects
				(font
					(size 0.7874 0.5842)
					(thickness 0.1524)
				)
				(justify left)
			)
		)
		(property "Value" ""
			(at 0 0 90)
			(layer "F.Fab")
			(effects
				(font
					(size 1.27 1.27)
				)
			)
		)
		(duplicate_pad_numbers_are_jumpers no)
		(fp_line
			(start 4.99999 -2.100072)
			(end -4.99999 -2.100072)
			(stroke
				(width 0.1524)
				(type default)
			)
			(layer "F.SilkS")
		)
		(fp_line
			(start -4.99999 -2.100072)
			(end -4.99999 0)
			(stroke
				(width 0.1524)
				(type default)
			)
			(layer "F.SilkS")
		)
		(fp_line
			(start 4.500118 -1.599946)
			(end 4.500118 2.100072)
			(stroke
				(width 0.1524)
				(type default)
			)
			(layer "F.SilkS")
		)
		(fp_line
			(start -2.3876 -1.599946)
			(end 4.500118 -1.599946)
			(stroke
				(width 0.1524)
				(type default)
			)
			(layer "F.SilkS")
		)
		(fp_line
			(start -4.500118 -1.599946)
			(end -3.6068 -1.599946)
			(stroke
				(width 0.1524)
				(type default)
			)
			(layer "F.SilkS")
		)
		(fp_line
			(start -4.99999 0)
			(end -4.99999 2.599944)
			(stroke
				(width 0.1524)
				(type default)
			)
			(layer "F.SilkS")
		)
		(fp_line
			(start 4.500118 2.100072)
			(end 1.999996 2.100072)
			(stroke
				(width 0.1524)
				(type default)
			)
			(layer "F.SilkS")
		)
		(fp_line
			(start 1.999996 2.100072)
			(end 1.999996 2.599944)
			(stroke
				(width 0.1524)
				(type default)
			)
			(layer "F.SilkS")
		)
		(fp_line
			(start -1.999996 2.100072)
			(end -4.500118 2.100072)
			(stroke
				(width 0.1524)
				(type default)
			)
			(layer "F.SilkS")
		)
		(fp_line
			(start -4.500118 2.100072)
			(end -4.500118 -1.599946)
			(stroke
				(width 0.1524)
				(type default)
			)
			(layer "F.SilkS")
		)
		(fp_line
			(start 4.99999 2.599944)
			(end 4.99999 -2.100072)
			(stroke
				(width 0.1524)
				(type default)
			)
			(layer "F.SilkS")
		)
		(fp_line
			(start -1.999996 2.599944)
			(end -1.999996 2.100072)
			(stroke
				(width 0.1524)
				(type default)
			)
			(layer "F.SilkS")
		)
		(fp_line
			(start -4.99999 2.599944)
			(end 4.99999 2.599944)
			(stroke
				(width 0.1524)
				(type default)
			)
			(layer "F.SilkS")
		)
		(fp_poly
			(pts
				(xy 5.115306 -0.578358) (xy 6.639306 -1.340358) (xy 6.639306 0.183642)
			)
			(stroke
				(width 0)
				(type default)
			)
			(fill yes)
			(layer "F.SilkS")
		)
		(fp_poly
			(pts
				(xy -3.7084 0.1778) (xy 3.683 0.1778) (xy 3.683 1.6256) (xy -3.7084 1.6256)
			)
			(stroke
				(width 0)
				(type default)
			)
			(fill no)
			(layer "B.CrtYd")
		)
		(fp_poly
			(pts
				(arc
					(start -2.9972 -1.7526)
					(mid -3.607857 -1.499657)
					(end -3.8608 -0.889)
				)
				(arc
					(start -3.8608 -0.889)
					(mid -3.615297 -0.296303)
					(end -3.0226 -0.0508)
				)
				(arc
					(start -2.9972 -0.0508)
					(mid -2.1463 -0.9017)
					(end -2.9972 -1.7526)
				)
			)
			(stroke
				(width 0)
				(type default)
			)
			(fill no)
			(layer "B.CrtYd")
		)
		(fp_rect
			(start -4.99999 2.599944)
			(end 4.99999 -2.100072)
			(stroke
				(width 0)
				(type default)
			)
			(fill no)
			(layer "F.CrtYd")
		)
		(fp_line
			(start 4.99999 -2.100072)
			(end -4.99999 -2.100072)
			(stroke
				(width 0.1)
				(type default)
			)
			(layer "F.Fab")
		)
		(fp_line
			(start -4.99999 -2.100072)
			(end -4.99999 0)
			(stroke
				(width 0.1)
				(type default)
			)
			(layer "F.Fab")
		)
		(fp_line
			(start 4.500118 -1.599946)
			(end 4.500118 2.100072)
			(stroke
				(width 0.1)
				(type default)
			)
			(layer "F.Fab")
		)
		(fp_line
			(start -3.6576 -1.599946)
			(end 4.500118 -1.599946)
			(stroke
				(width 0.1)
				(type default)
			)
			(layer "F.Fab")
		)
		(fp_line
			(start -4.500118 -1.599946)
			(end -3.6068 -1.599946)
			(stroke
				(width 0.1)
				(type default)
			)
			(layer "F.Fab")
		)
		(fp_line
			(start -4.99999 0)
			(end -4.99999 2.599944)
			(stroke
				(width 0.1)
				(type default)
			)
			(layer "F.Fab")
		)
		(fp_line
			(start 4.500118 2.100072)
			(end 1.999996 2.100072)
			(stroke
				(width 0.1)
				(type default)
			)
			(layer "F.Fab")
		)
		(fp_line
			(start 1.999996 2.100072)
			(end 1.999996 2.599944)
			(stroke
				(width 0.1)
				(type default)
			)
			(layer "F.Fab")
		)
		(fp_line
			(start -1.999996 2.100072)
			(end -4.500118 2.100072)
			(stroke
				(width 0.1)
				(type default)
			)
			(layer "F.Fab")
		)
		(fp_line
			(start -4.500118 2.100072)
			(end -4.500118 -1.599946)
			(stroke
				(width 0.1)
				(type default)
			)
			(layer "F.Fab")
		)
		(fp_line
			(start 4.99999 2.599944)
			(end 4.99999 -2.100072)
			(stroke
				(width 0.1)
				(type default)
			)
			(layer "F.Fab")
		)
		(fp_line
			(start -1.999996 2.599944)
			(end -1.999996 2.100072)
			(stroke
				(width 0.1)
				(type default)
			)
			(layer "F.Fab")
		)
		(fp_line
			(start -4.99999 2.599944)
			(end 4.99999 2.599944)
			(stroke
				(width 0.1)
				(type default)
			)
			(layer "F.Fab")
		)
		(fp_poly
			(pts
				(xy 5.715 0.899922) (xy 7.239 0.137922) (xy 7.239 1.661922)
			)
			(stroke
				(width 0)
				(type default)
			)
			(fill yes)
			(layer "F.Fab")
		)
		(fp_text user "1"
			(at 4.39674 -2.86766 0)
			(unlocked yes)
			(layer "F.SilkS")
			(effects
				(font
					(size 0.7874 0.5842)
					(thickness 0.1524)
				)
				(justify left)
			)
		)
		(fp_text user "4"
			(at -5.4356 -0.850646 0)
			(unlocked yes)
			(layer "F.SilkS")
			(effects
				(font
					(size 0.7874 0.5842)
					(thickness 0.1524)
				)
				(justify left)
			)
		)
		(fp_text user "4"
			(at -4.471162 1.331214 0)
			(unlocked yes)
			(layer "B.SilkS")
			(effects
				(font
					(size 0.7874 0.5842)
					(thickness 0.1524)
				)
				(justify left mirror)
			)
		)
		(fp_text user "1"
			(at 3.991864 2.68732 0)
			(unlocked yes)
			(layer "B.SilkS")
			(effects
				(font
					(size 0.7874 0.5842)
					(thickness 0.1524)
				)
				(justify left mirror)
			)
		)
		(fp_text user "1"
			(at 4.4831 0.808203 90)
			(unlocked yes)
			(layer "B.Fab")
			(effects
				(font
					(size 0.786892 0.583946)
					(thickness 0.000001)
				)
				(justify left mirror)
			)
		)
		(fp_text user "4"
			(at -3.8989 0.808203 90)
			(unlocked yes)
			(layer "B.Fab")
			(effects
				(font
					(size 0.786892 0.583946)
					(thickness 0.000001)
				)
				(justify left mirror)
			)
		)
		(fp_text user "1"
			(at 5.0419 0.808203 90)
			(unlocked yes)
			(layer "F.Fab")
			(effects
				(font
					(size 0.786892 0.583946)
					(thickness 0.000001)
				)
				(justify left)
			)
		)
		(fp_text user "4"
			(at -6.0071 0.808203 90)
			(unlocked yes)
			(layer "F.Fab")
			(effects
				(font
					(size 0.786892 0.583946)
					(thickness 0.000001)
				)
				(justify left)
			)
		)
		(pad "" np_thru_hole circle
			(at -2.999994 -0.899922 90)
			(size 1.1938 1.1938)
			(drill 1.1938)
			(layers "*.Cu" "*.Mask")
			(clearance 0.381)
			(thermal_gap 0.381)
		)
		(pad "1" thru_hole rect
			(at 2.999994 0.899922 90)
			(size 1.3208 1.3208)
			(drill 0.9144)
			(layers "*.Cu" "*.Mask")
			(remove_unused_layers no)
			(net "P3V3_NODE1")
			(clearance 0.0508)
			(thermal_gap 0.0508)
			(padstack
				(mode front_inner_back)
				(layer "Inner"
					(shape circle)
					(size 1.3208 1.3208)
					(clearance 0.0508)
				)
				(layer "B.Cu"
					(shape rect)
					(size 1.3208 1.3208)
					(clearance 0.0508)
				)
			)
		)
		(pad "2" thru_hole circle
			(at 0.999998 0.899922 90)
			(size 1.3208 1.3208)
			(drill 0.9144)
			(layers "*.Cu" "*.Mask")
			(remove_unused_layers no)
			(net "UART_TX_P4")
			(clearance 0.0508)
			(thermal_gap 0.0508)
		)
		(pad "3" thru_hole circle
			(at -0.999998 0.899922 90)
			(size 1.3208 1.3208)
			(drill 0.9144)
			(layers "*.Cu" "*.Mask")
			(remove_unused_layers no)
			(net "UART_RX_P4_BUF")
			(clearance 0.0508)
			(thermal_gap 0.0508)
		)
		(pad "4" thru_hole circle
			(at -2.999994 0.899922 90)
			(size 1.3208 1.3208)
			(drill 0.9144)
			(layers "*.Cu" "*.Mask")
			(remove_unused_layers no)
			(net "GND")
			(clearance 0.0508)
			(thermal_gap 0.0508)
		)
		(zone
			(layers "F.Cu" "B.Cu" "In1.Cu" "In2.Cu" "In3.Cu" "In4.Cu" "In5.Cu" "In6.Cu"
				"In7.Cu" "In8.Cu"
			)
			(hatch none 0.5)
			(connect_pads
				(clearance 0)
			)
			(min_thickness 0.25)
			(keepout
				(tracks not_allowed)
				(vias allowed)
				(pads allowed)
				(copperpour not_allowed)
				(footprints allowed)
			)
			(placement
				(enabled no)
				(sheetname "")
			)
			(fill
				(thermal_gap 0.5)
				(thermal_bridge_width 0.5)
				(island_removal_mode 0)
			)
			(polygon
				(pts
					(arc
						(start 147.308824 -17.571212)
						(mid 147.606404 -16.852792)
						(end 148.324824 -16.555212)
					)
					(arc
						(start 148.324824 -16.555212)
						(mid 149.025284 -16.845352)
						(end 149.315424 -17.545812)
					)
					(arc
						(start 149.315424 -17.571212)
						(mid 148.312124 -18.574512)
						(end 147.308824 -17.571212)
					)
				)
			)
		)
	)
	(footprint ""
		(layer "F.Cu")
		(at 132.31876 -188.126624 90)
		(property "Reference" "C752"
			(at 4.949444 -0.957072 90)
			(unlocked yes)
			(layer "F.SilkS")
			(effects
				(font
					(size 0.7874 0.5842)
					(thickness 0.1524)
				)
				(justify left)
			)
		)
		(property "Value" ""
			(at 0 0 90)
			(layer "F.Fab")
			(effects
				(font
					(size 1.27 1.27)
				)
			)
		)
		(duplicate_pad_numbers_are_jumpers no)
		(fp_line
			(start 0.7874 -0.4064)
			(end 0.7874 0.4064)
			(stroke
				(width 0.1524)
				(type default)
			)
			(layer "F.SilkS")
		)
		(fp_line
			(start -0.7874 -0.4064)
			(end 0.7874 -0.4064)
			(stroke
				(width 0.1524)
				(type default)
			)
			(layer "F.SilkS")
		)
		(fp_line
			(start 0 0.381)
			(end 0 -0.381)
			(stroke
				(width 0.1524)
				(type default)
			)
			(layer "F.SilkS")
		)
		(fp_line
			(start 0.7874 0.4064)
			(end -0.7874 0.4064)
			(stroke
				(width 0.1524)
				(type default)
			)
			(layer "F.SilkS")
		)
		(fp_line
			(start -0.7874 0.4064)
			(end -0.7874 -0.4064)
			(stroke
				(width 0.1524)
				(type default)
			)
			(layer "F.SilkS")
		)
		(fp_poly
			(pts
				(xy -0.5334 0.254) (xy -0.635 0.254) (xy -0.635 0.2286) (xy -0.635 -0.254) (xy -0.5334 -0.254) (xy -0.5334 -0.2794)
				(xy 0.5334 -0.2794) (xy 0.5334 -0.254) (xy 0.635 -0.254) (xy 0.635 0.254) (xy 0.5334 0.254) (xy 0.5334 0.2794)
				(xy -0.508 0.2794) (xy -0.5334 0.2794)
			)
			(stroke
				(width 0)
				(type default)
			)
			(fill no)
			(layer "F.CrtYd")
		)
		(pad "1" smd rect
			(at 0.40005 0 90)
			(size 0.4572 0.508)
			(layers "F.Cu" "F.Mask" "F.Paste")
			(net "UART_T10_NODE2_TXD_R")
		)
		(pad "2" smd rect
			(at -0.40005 0 90)
			(size 0.4572 0.508)
			(layers "F.Cu" "F.Mask" "F.Paste")
			(net "GND")
		)
	)
	(footprint ""
		(layer "F.Cu")
		(at 149.392894 -45.70857)
		(property "Reference" "R626"
			(at -2.3368 -2.962148 0)
			(unlocked yes)
			(layer "F.SilkS")
			(effects
				(font
					(size 0.7874 0.5842)
					(thickness 0.1524)
				)
				(justify left)
			)
		)
		(property "Value" ""
			(at 0 0 0)
			(layer "F.Fab")
			(effects
				(font
					(size 1.27 1.27)
				)
			)
		)
		(duplicate_pad_numbers_are_jumpers no)
		(fp_line
			(start -0.7874 -0.4064)
			(end 0.7874 -0.4064)
			(stroke
				(width 0.1524)
				(type default)
			)
			(layer "F.SilkS")
		)
		(fp_line
			(start -0.7874 0.4064)
			(end -0.7874 -0.4064)
			(stroke
				(width 0.1524)
				(type default)
			)
			(layer "F.SilkS")
		)
		(fp_line
			(start 0.7874 -0.4064)
			(end 0.7874 0.4064)
			(stroke
				(width 0.1524)
				(type default)
			)
			(layer "F.SilkS")
		)
		(fp_line
			(start 0.7874 0.4064)
			(end -0.7874 0.4064)
			(stroke
				(width 0.1524)
				(type default)
			)
			(layer "F.SilkS")
		)
		(fp_poly
			(pts
				(xy -0.508 0.2794) (xy -0.508 0.2286) (xy -0.635 0.2286) (xy -0.635 -0.254) (xy -0.5334 -0.254)
				(xy -0.5334 -0.2794) (xy 0.5334 -0.2794) (xy 0.5334 -0.254) (xy 0.635 -0.254) (xy 0.635 0.254) (xy 0.5334 0.254)
				(xy 0.5334 0.2794)
			)
			(stroke
				(width 0)
				(type default)
			)
			(fill no)
			(layer "F.CrtYd")
		)
		(pad "1" smd rect
			(at 0.40005 0)
			(size 0.4572 0.508)
			(layers "F.Cu" "F.Mask" "F.Paste")
			(net "P3V3_NODE1")
		)
		(pad "2" smd rect
			(at -0.40005 0)
			(size 0.4572 0.508)
			(layers "F.Cu" "F.Mask" "F.Paste")
			(net "UART_RI_P2_N")
		)
	)
)
